G04 ================== begin FILE IDENTIFICATION RECORD ==================*
G04 Layout Name:  13130-1b.brd*
G04 Film Name:    WSILK_T*
G04 File Format:  Gerber RS274X*
G04 File Origin:  Cadence Allegro 16.5-S037*
G04 Origin Date:  Thu Nov 13 17:26:41 2014*
G04 *
G04 Layer:  DRAWING FORMAT/LAYER_WSILK_T*
G04 Layer:  DRAWING FORMAT/LAYER_PCB_STORY*
G04 Layer:  BOARD GEOMETRY/WSILK_T*
G04 Layer:  BOARD GEOMETRY/PANEL_OUTLINE*
G04 *
G04 Offset:    (0.00 0.00)*
G04 Mirror:    No*
G04 Mode:      Positive*
G04 Rotation:  0*
G04 FullContactRelief:  No*
G04 UndefLineWidth:     6.00*
G04 ================== end FILE IDENTIFICATION RECORD ====================*
%FSLAX35Y35*MOIN*%
%IR0*IPPOS*OFA0.00000B0.00000*MIA0B0*SFA1.00000B1.00000*%
%ADD10C,.02*%
%ADD11C,.006*%
G75*
%LPD*%
G75*
G54D10*
G01X10636Y-27865D02*
G02I-12000J0D01*
G01X14636D02*
X-17364D01*
G01X5486D02*
G02I-6850J0D01*
G01X-1364Y-43865D02*
Y-11865D01*
G01X14636Y-43865D02*
Y-123865D01*
G01D02*
X1309236D01*
G01X14636Y-79365D02*
X1309236D01*
G01X14636Y-43865D02*
X1309236D01*
G01X521736D02*
Y-123865D01*
G01X659236Y-43865D02*
Y-123865D01*
G01X774236Y-43865D02*
Y-123865D01*
G01X941736Y-43865D02*
Y-123865D01*
G01X1111736Y-43865D02*
Y-123865D01*
G01X1309236Y-43865D02*
Y-123865D01*
G01X1341236Y-27865D02*
X1309236D01*
G01X1337236D02*
G02I-12000J0D01*
G01X1332086D02*
G02I-6850J0D01*
G01X1325236Y-43865D02*
Y-11865D01*
G54D11*
G01X-31497Y-1D02*
X26377D01*
G01X-35434Y3936D02*
G03X-31497Y-1I3937J0D01*
G01X-35434Y585039D02*
Y3936D01*
G01X-7874Y588976D02*
X-31497D01*
G01D02*
G03X-35434Y585039I0J-3937D01*
G01X-12698Y15747D02*
G03I-6988J0D01*
G01Y573227D02*
G03I-6988J0D01*
G01X826773Y286614D02*
G03X822836Y290551I-3937J0D01*
G01X3938D01*
G03X1Y286614I0J-3937D01*
G01Y61811D01*
G03X3938Y57874I3937J0D01*
G01X53938D01*
G02X57875Y53937I0J-3937D01*
G01Y12598D01*
X59844Y10629D01*
X336222D01*
X338190Y12598D01*
Y39960D01*
G02X345671I3740J0D01*
G01Y12598D01*
X347639Y10629D01*
X387797D01*
X389765Y12598D01*
Y42126D01*
G02X393702Y46063I3937J0D01*
G01X409450D01*
G02X413387Y42126I0J-3937D01*
G01Y3937D01*
G03X417324Y0I3937J0D01*
G01X822836D01*
G03X826773Y3937I0J3937D01*
G01Y286614D01*
G01X22440Y49999D02*
X-3937D01*
G01X-7874Y53936D02*
Y72440D01*
G01Y53936D02*
G03X-3937Y49999I3937J0D01*
G01X0Y72440D02*
G03X-7874I-3937J0D01*
G01Y103149D02*
G03X0I3937J0D01*
G01X-7874D02*
Y210235D01*
G01X0D02*
G03X-7874I-3937J0D01*
G01Y240944D02*
Y348031D01*
G01Y240944D02*
G03X0I3937J0D01*
G01X-3Y302361D02*
G03X3934Y298424I3937J0D01*
G01X822832D01*
G03X826769Y302361I0J3937D01*
G01Y527164D01*
G03X822832Y531101I-3937J0D01*
G01X772832D01*
G02X768895Y535038I0J3937D01*
G01Y576377D01*
X766926Y578346D01*
X490548D01*
X488580Y576377D01*
Y549015D01*
G02X481099I-3740J0D01*
G01Y576377D01*
X479131Y578346D01*
X438973D01*
X437005Y576377D01*
Y546849D01*
G02X433068Y542912I-3937J0D01*
G01X417320D01*
G02X413383Y546849I0J3937D01*
G01Y585038D01*
G03X409446Y588975I-3937J0D01*
G01X3934D01*
G03X-3Y585038I0J-3937D01*
G01Y302361D01*
G01X0Y348031D02*
G03X-7874I-3937J0D01*
G01Y378739D02*
Y485826D01*
G01Y378739D02*
G03X0I3937J0D01*
G01Y485826D02*
G03X-7874I-3937J0D01*
G01Y516535D02*
Y588976D01*
G01Y516535D02*
G03X0I3937J-1D01*
G01X26377Y-1D02*
Y46062D01*
G01D02*
G03X22440Y49999I-3937J0D01*
G01X70851Y-113865D02*
Y-96365D01*
G01X80021D02*
Y-113865D01*
G01Y-105115D02*
X70851D01*
G01X92936Y-113865D02*
X91626Y-113573D01*
X90316Y-112407D01*
X89442Y-110365D01*
X89006Y-108032D01*
X89442Y-105698D01*
X90316Y-103657D01*
X91626Y-102490D01*
X92936Y-102199D01*
X94246Y-102490D01*
X95556Y-103657D01*
X96429Y-105698D01*
X96648Y-108032D01*
X96429Y-110365D01*
X95556Y-112407D01*
X94246Y-113573D01*
X92936Y-113865D01*
G01X106724D02*
Y-102199D01*
G01Y-105115D02*
X107598Y-103657D01*
X108908Y-102490D01*
X110654Y-102199D01*
X112182Y-102490D01*
X113493Y-103657D01*
X114148Y-105698D01*
Y-113865D01*
G01X124661Y-105990D02*
X131648D01*
X130993Y-103948D01*
X129901Y-102782D01*
X128373Y-102199D01*
X126844Y-102490D01*
X125534Y-103365D01*
X124661Y-105407D01*
X124224Y-107157D01*
Y-108907D01*
X124661Y-110657D01*
X125753Y-112407D01*
X127063Y-113573D01*
X128591Y-113865D01*
X130119Y-113282D01*
X131648Y-111532D01*
G01X140851Y-119115D02*
X142161Y-119698D01*
X143908Y-119115D01*
X144999Y-117949D01*
X145873Y-116490D01*
X147182Y-111824D01*
X150021Y-102199D01*
G01X143034D02*
X147182Y-111824D01*
G01X182182Y-104532D02*
X183056Y-103657D01*
X183711Y-102199D01*
X184148Y-100156D01*
X183711Y-98407D01*
X182838Y-97240D01*
X181309Y-96365D01*
X175414D01*
Y-113865D01*
X182619D01*
X184148Y-112699D01*
X185021Y-110948D01*
X185458Y-108907D01*
X185021Y-106865D01*
X183711Y-105115D01*
X182182Y-104532D01*
X175414D01*
G01X201866Y-113865D02*
Y-102199D01*
G01Y-104240D02*
X200993Y-103074D01*
X199682Y-102490D01*
X198154Y-102199D01*
X196626Y-102782D01*
X195316Y-103948D01*
X194442Y-105698D01*
X194006Y-108032D01*
X194442Y-110365D01*
X195316Y-112115D01*
X196626Y-113282D01*
X198154Y-113865D01*
X199682Y-113573D01*
X200993Y-112699D01*
X201866Y-111532D01*
G01X219366Y-96365D02*
Y-113865D01*
G01Y-111241D02*
X218493Y-112699D01*
X217182Y-113573D01*
X215654Y-113865D01*
X213908Y-113282D01*
X212598Y-111824D01*
X211724Y-110074D01*
X211506Y-108032D01*
X211724Y-105990D01*
X212598Y-104240D01*
X213908Y-102782D01*
X215654Y-102199D01*
X217182Y-102490D01*
X218274Y-103074D01*
X219366Y-104240D01*
G01X229879Y-118240D02*
X231408Y-119407D01*
X233154Y-119698D01*
X234682Y-119407D01*
X235993Y-117949D01*
X236866Y-115907D01*
Y-102199D01*
G01Y-104532D02*
X235993Y-103365D01*
X234682Y-102490D01*
X233154Y-102199D01*
X231408Y-102782D01*
X230316Y-103948D01*
X229442Y-105990D01*
X229006Y-108032D01*
X229224Y-109782D01*
X230098Y-111824D01*
X231408Y-113282D01*
X233154Y-113865D01*
X234464Y-113573D01*
X235993Y-112407D01*
X236866Y-111241D01*
G01X247161Y-105990D02*
X254148D01*
X253493Y-103948D01*
X252401Y-102782D01*
X250873Y-102199D01*
X249344Y-102490D01*
X248034Y-103365D01*
X247161Y-105407D01*
X246724Y-107157D01*
Y-108907D01*
X247161Y-110657D01*
X248253Y-112407D01*
X249563Y-113573D01*
X251091Y-113865D01*
X252619Y-113282D01*
X254148Y-111532D01*
G01X264879Y-113865D02*
Y-102199D01*
G01Y-104532D02*
X265971Y-103365D01*
X267063Y-102490D01*
X268591Y-102199D01*
X269682Y-102490D01*
X270993Y-103365D01*
G01X298569Y-113865D02*
Y-96365D01*
X303809D01*
X305556Y-97240D01*
X306866Y-99282D01*
X307303Y-101615D01*
X306866Y-103948D01*
X305774Y-105698D01*
X303809Y-106574D01*
X298569D01*
G01X324366Y-113865D02*
Y-102199D01*
G01Y-104240D02*
X323493Y-103074D01*
X322182Y-102490D01*
X320654Y-102199D01*
X319126Y-102782D01*
X317816Y-103948D01*
X316942Y-105698D01*
X316506Y-108032D01*
X316942Y-110365D01*
X317816Y-112115D01*
X319126Y-113282D01*
X320654Y-113865D01*
X322182Y-113573D01*
X323493Y-112699D01*
X324366Y-111532D01*
G01X334224Y-113865D02*
Y-102199D01*
G01Y-105115D02*
X335098Y-103657D01*
X336408Y-102490D01*
X338154Y-102199D01*
X339682Y-102490D01*
X340993Y-103657D01*
X341648Y-105698D01*
Y-113865D01*
G01X355436Y-96365D02*
Y-113865D01*
G01X352379Y-102199D02*
X358493D01*
G01X369224Y-113865D02*
Y-96365D01*
G01Y-104823D02*
X370316Y-103365D01*
X371408Y-102490D01*
X373154Y-102199D01*
X374464Y-102490D01*
X375993Y-103657D01*
X376648Y-105407D01*
Y-113865D01*
G01X387161Y-105990D02*
X394148D01*
X393493Y-103948D01*
X392401Y-102782D01*
X390873Y-102199D01*
X389344Y-102490D01*
X388034Y-103365D01*
X387161Y-105407D01*
X386724Y-107157D01*
Y-108907D01*
X387161Y-110657D01*
X388253Y-112407D01*
X389563Y-113573D01*
X391091Y-113865D01*
X392619Y-113282D01*
X394148Y-111532D01*
G01X404879Y-113865D02*
Y-102199D01*
G01Y-104532D02*
X405971Y-103365D01*
X407063Y-102490D01*
X408591Y-102199D01*
X409682Y-102490D01*
X410993Y-103365D01*
G01X437259Y-113865D02*
Y-96365D01*
X442936Y-110948D01*
X448613Y-96365D01*
Y-113865D01*
G01X462182Y-104532D02*
X463056Y-103657D01*
X463711Y-102199D01*
X464148Y-100156D01*
X463711Y-98407D01*
X462838Y-97240D01*
X461309Y-96365D01*
X455414D01*
Y-113865D01*
X462619D01*
X464148Y-112699D01*
X465021Y-110948D01*
X465458Y-108907D01*
X465021Y-106865D01*
X463711Y-105115D01*
X462182Y-104532D01*
X455414D01*
G01X102756Y290550D02*
G03Y298424I0J3937D01*
G01X133465D02*
G03Y290550I0J-3937D01*
G01X227259Y-68865D02*
Y-51365D01*
X232936Y-65948D01*
X238613Y-51365D01*
Y-68865D01*
G01X250436D02*
X249126Y-68573D01*
X247816Y-67407D01*
X246942Y-65365D01*
X246506Y-63032D01*
X246942Y-60698D01*
X247816Y-58657D01*
X249126Y-57490D01*
X250436Y-57199D01*
X251746Y-57490D01*
X253056Y-58657D01*
X253929Y-60698D01*
X254148Y-63032D01*
X253929Y-65365D01*
X253056Y-67407D01*
X251746Y-68573D01*
X250436Y-68865D01*
G01X271866Y-51365D02*
Y-68865D01*
G01Y-66241D02*
X270993Y-67699D01*
X269682Y-68573D01*
X268154Y-68865D01*
X266408Y-68282D01*
X265098Y-66824D01*
X264224Y-65074D01*
X264006Y-63032D01*
X264224Y-60990D01*
X265098Y-59240D01*
X266408Y-57782D01*
X268154Y-57199D01*
X269682Y-57490D01*
X270774Y-58074D01*
X271866Y-59240D01*
G01X282161Y-60990D02*
X289148D01*
X288493Y-58948D01*
X287401Y-57782D01*
X285873Y-57199D01*
X284344Y-57490D01*
X283034Y-58365D01*
X282161Y-60407D01*
X281724Y-62157D01*
Y-63907D01*
X282161Y-65657D01*
X283253Y-67407D01*
X284563Y-68573D01*
X286091Y-68865D01*
X287619Y-68282D01*
X289148Y-66532D01*
G01X302936Y-68865D02*
Y-51365D01*
G01X299606Y290551D02*
G03Y298425I0J3937D01*
G01X330314D02*
G03Y290551I0J-3937D01*
G01X496457Y290550D02*
G03Y298424I0J3937D01*
G01X527166D02*
G03Y290550I0J-3937D01*
G01X542319Y-68865D02*
Y-51365D01*
X547559D01*
X549306Y-52240D01*
X550616Y-54282D01*
X551053Y-56615D01*
X550616Y-58948D01*
X549524Y-60698D01*
X547559Y-61574D01*
X542319D01*
G01X568989Y-52824D02*
X567679Y-51948D01*
X566151Y-51365D01*
X564404D01*
X562439Y-52240D01*
X560911Y-53698D01*
X559819Y-55449D01*
X558946Y-58365D01*
X558727Y-60990D01*
X559164Y-63615D01*
X559819Y-65365D01*
X561129Y-67115D01*
X562658Y-68282D01*
X564186Y-68865D01*
X565714D01*
X567243Y-68282D01*
X568553Y-67407D01*
X569645Y-66241D01*
G01X583432Y-59532D02*
X584306Y-58657D01*
X584961Y-57199D01*
X585398Y-55156D01*
X584961Y-53407D01*
X584088Y-52240D01*
X582559Y-51365D01*
X576664D01*
Y-68865D01*
X583869D01*
X585398Y-67699D01*
X586271Y-65948D01*
X586708Y-63907D01*
X586271Y-61865D01*
X584961Y-60115D01*
X583432Y-59532D01*
X576664D01*
G01X592636Y-74698D02*
X605736D01*
G01X611664Y-68865D02*
Y-51365D01*
X621708Y-68865D01*
Y-51365D01*
G01X634186Y-68865D02*
X632439Y-68573D01*
X630911Y-67407D01*
X629601Y-65657D01*
X628727Y-63615D01*
X628291Y-61282D01*
Y-58948D01*
X628727Y-56615D01*
X629601Y-54573D01*
X630911Y-52824D01*
X632439Y-51657D01*
X634186Y-51365D01*
X635932Y-51657D01*
X637461Y-52824D01*
X638771Y-54573D01*
X639645Y-56615D01*
X640081Y-58948D01*
Y-61282D01*
X639645Y-63615D01*
X638771Y-65657D01*
X637461Y-67407D01*
X635932Y-68573D01*
X634186Y-68865D01*
G01X555436Y-113865D02*
Y-96365D01*
X552816Y-99865D01*
G01Y-113865D02*
X558056D01*
G01X568133Y-110365D02*
X569442Y-112407D01*
X571189Y-113573D01*
X573154Y-113865D01*
X574901Y-113573D01*
X576648Y-112115D01*
X577739Y-110365D01*
X577958Y-108615D01*
X577521Y-106574D01*
X575993Y-105115D01*
X574464Y-104532D01*
X572499D01*
G01X574464D02*
X575774Y-103657D01*
X576866Y-102199D01*
X577303Y-100449D01*
X576866Y-98698D01*
X575774Y-97240D01*
X573809Y-96365D01*
X571844Y-96657D01*
X569879Y-97824D01*
G01X590436Y-113865D02*
Y-96365D01*
X587816Y-99865D01*
G01Y-113865D02*
X593056D01*
G01X603133Y-110365D02*
X604442Y-112407D01*
X606189Y-113573D01*
X608154Y-113865D01*
X609901Y-113573D01*
X611648Y-112115D01*
X612739Y-110365D01*
X612958Y-108615D01*
X612521Y-106574D01*
X610993Y-105115D01*
X609464Y-104532D01*
X607499D01*
G01X609464D02*
X610774Y-103657D01*
X611866Y-102199D01*
X612303Y-100449D01*
X611866Y-98698D01*
X610774Y-97240D01*
X608809Y-96365D01*
X606844Y-96657D01*
X604879Y-97824D01*
G01X625436Y-96365D02*
X623689Y-96948D01*
X622379Y-98407D01*
X621506Y-100156D01*
X620851Y-102490D01*
X620633Y-105115D01*
X620851Y-107740D01*
X621506Y-110074D01*
X622379Y-111824D01*
X623689Y-113282D01*
X625436Y-113865D01*
X627182Y-113282D01*
X628493Y-111824D01*
X629366Y-110074D01*
X630021Y-107740D01*
X630239Y-105115D01*
X630021Y-102490D01*
X629366Y-100156D01*
X628493Y-98407D01*
X627182Y-96948D01*
X625436Y-96365D01*
G01X685027Y-51365D02*
X690486Y-68865D01*
X695945Y-51365D01*
G01X712353Y-68865D02*
X703619D01*
Y-51365D01*
X712353D01*
G01X708859Y-59823D02*
X703619D01*
G01X721119Y-68865D02*
Y-51365D01*
X726578D01*
X728324Y-52240D01*
X729416Y-53407D01*
X729853Y-55740D01*
X729416Y-58074D01*
X728106Y-59532D01*
X726578Y-60407D01*
X721119D01*
G01X726578D02*
X729853Y-68865D01*
G01X742986Y-69448D02*
X742549Y-69157D01*
Y-68573D01*
X742986Y-68282D01*
X743423Y-68573D01*
Y-69157D01*
X742986Y-69448D01*
G01X693308Y290550D02*
G03Y298424I0J3937D01*
G01X707986Y-113865D02*
Y-96365D01*
X705366Y-99865D01*
G01Y-113865D02*
X710606D01*
G01X727232Y-104532D02*
X728106Y-103657D01*
X728761Y-102199D01*
X729198Y-100156D01*
X728761Y-98407D01*
X727888Y-97240D01*
X726359Y-96365D01*
X720464D01*
Y-113865D01*
X727669D01*
X729198Y-112699D01*
X730071Y-110948D01*
X730508Y-108907D01*
X730071Y-106865D01*
X728761Y-105115D01*
X727232Y-104532D01*
X720464D01*
G01X724016Y298424D02*
G03Y290550I0J-3937D01*
G01X800393Y588976D02*
Y542913D01*
G01D02*
G03X804330Y538976I3937J0D01*
G01X858267Y588976D02*
X800393D01*
G01X818569Y-51365D02*
Y-68865D01*
X827303D01*
G01X844366D02*
Y-57199D01*
G01Y-59240D02*
X843493Y-58074D01*
X842182Y-57490D01*
X840654Y-57199D01*
X839126Y-57782D01*
X837816Y-58948D01*
X836942Y-60698D01*
X836506Y-63032D01*
X836942Y-65365D01*
X837816Y-67115D01*
X839126Y-68282D01*
X840654Y-68865D01*
X842182Y-68573D01*
X843493Y-67699D01*
X844366Y-66532D01*
G01X853351Y-74115D02*
X854661Y-74698D01*
X856408Y-74115D01*
X857499Y-72949D01*
X858373Y-71490D01*
X859682Y-66824D01*
X862521Y-57199D01*
G01X855534D02*
X859682Y-66824D01*
G01X872161Y-60990D02*
X879148D01*
X878493Y-58948D01*
X877401Y-57782D01*
X875873Y-57199D01*
X874344Y-57490D01*
X873034Y-58365D01*
X872161Y-60407D01*
X871724Y-62157D01*
Y-63907D01*
X872161Y-65657D01*
X873253Y-67407D01*
X874563Y-68573D01*
X876091Y-68865D01*
X877619Y-68282D01*
X879148Y-66532D01*
G01X889879Y-68865D02*
Y-57199D01*
G01Y-59532D02*
X890971Y-58365D01*
X892063Y-57490D01*
X893591Y-57199D01*
X894682Y-57490D01*
X895993Y-58365D01*
G01X804330Y538976D02*
X830708D01*
G01X834645Y72440D02*
G03X826771I-3937J0D01*
G01Y103149D02*
G03X834645I3937J0D01*
G01Y210235D02*
G03X826771I-3937J0D01*
G01Y240944D02*
G03X834645I3937J0D01*
G01Y348031D02*
G03X826771I-3937J0D01*
G01Y378739D02*
G03X834645I3937J0D01*
G01Y485826D02*
G03X826771I-3937J0D01*
G01Y516535D02*
G03X834645I3937J-1D01*
G01Y535039D02*
G03X830708Y538976I-3937J0D01*
G01X834645Y72440D02*
Y-1D01*
G01D02*
X858267D01*
G01X853444Y15747D02*
G03I-6988J0D01*
G01X834645Y210235D02*
Y103149D01*
G01Y348031D02*
Y240944D01*
G01Y485826D02*
Y378739D01*
G01Y535039D02*
Y516535D01*
G01X853444Y573227D02*
G03I-6988J0D01*
G01X862204Y3936D02*
Y585039D01*
G01X858267Y-1D02*
G03X862204Y3936I0J3937D01*
G01Y585039D02*
G03X858267Y588976I-3937J0D01*
G01X943619Y-110365D02*
X944711Y-112115D01*
X946021Y-113282D01*
X947549Y-113865D01*
X949296Y-113282D01*
X950606Y-112115D01*
X951916Y-110365D01*
X952353Y-108032D01*
Y-96365D01*
G01X965486Y-113865D02*
X963739Y-113573D01*
X962211Y-112407D01*
X960901Y-110657D01*
X960027Y-108615D01*
X959591Y-106282D01*
Y-103948D01*
X960027Y-101615D01*
X960901Y-99573D01*
X962211Y-97824D01*
X963739Y-96657D01*
X965486Y-96365D01*
X967232Y-96657D01*
X968761Y-97824D01*
X970071Y-99573D01*
X970945Y-101615D01*
X971381Y-103948D01*
Y-106282D01*
X970945Y-108615D01*
X970071Y-110657D01*
X968761Y-112407D01*
X967232Y-113573D01*
X965486Y-113865D01*
G01X978401Y-111532D02*
X980148Y-112990D01*
X982113Y-113865D01*
X983859D01*
X985606Y-112990D01*
X986916Y-111532D01*
X987571Y-109490D01*
X987134Y-107449D01*
X986043Y-105698D01*
X984078Y-104532D01*
X981458Y-103948D01*
X979929Y-102782D01*
X979274Y-100740D01*
X979711Y-98698D01*
X980803Y-97240D01*
X982331Y-96365D01*
X983859D01*
X985388Y-96948D01*
X986698Y-98407D01*
G01X1004853Y-113865D02*
X996119D01*
Y-96365D01*
X1004853D01*
G01X1001359Y-104823D02*
X996119D01*
G01X1013619Y-113865D02*
Y-96365D01*
X1018859D01*
X1020606Y-97240D01*
X1021916Y-99282D01*
X1022353Y-101615D01*
X1021916Y-103948D01*
X1020824Y-105698D01*
X1018859Y-106574D01*
X1013619D01*
G01X1030901Y-113865D02*
Y-96365D01*
G01X1040071D02*
Y-113865D01*
G01Y-105115D02*
X1030901D01*
G01X1066119Y-96365D02*
Y-113865D01*
X1074853D01*
G01X1082527D02*
X1087986Y-96365D01*
X1093445Y-113865D01*
G01X1091479Y-107740D02*
X1084492D01*
G01X1100683Y-96365D02*
Y-108907D01*
X1101556Y-111532D01*
X1103303Y-113282D01*
X1105486Y-113865D01*
X1107669Y-113282D01*
X1109416Y-111532D01*
X1110289Y-108907D01*
Y-96365D01*
G01X960683Y-68865D02*
Y-51365D01*
X965049D01*
X966796Y-52240D01*
X968106Y-53407D01*
X969198Y-55156D01*
X970071Y-57199D01*
X970289Y-60115D01*
X970071Y-63032D01*
X969198Y-65074D01*
X968106Y-66824D01*
X966796Y-67990D01*
X965049Y-68865D01*
X960683D01*
G01X979711Y-60990D02*
X986698D01*
X986043Y-58948D01*
X984951Y-57782D01*
X983423Y-57199D01*
X981894Y-57490D01*
X980584Y-58365D01*
X979711Y-60407D01*
X979274Y-62157D01*
Y-63907D01*
X979711Y-65657D01*
X980803Y-67407D01*
X982113Y-68573D01*
X983641Y-68865D01*
X985169Y-68282D01*
X986698Y-66532D01*
G01X997211Y-66824D02*
X998303Y-67990D01*
X999831Y-68865D01*
X1001141D01*
X1002451Y-68282D01*
X1003324Y-67407D01*
X1003761Y-66241D01*
X1003543Y-64490D01*
X1002669Y-63615D01*
X998739Y-61865D01*
X997866Y-59823D01*
X998303Y-58365D01*
X999176Y-57490D01*
X1000486Y-57199D01*
X1001796Y-57490D01*
X1003106Y-58365D01*
G01X1017986Y-57199D02*
Y-68865D01*
G01Y-52532D02*
X1017549Y-52240D01*
Y-51657D01*
X1017986Y-51365D01*
X1018423Y-51657D01*
Y-52240D01*
X1017986Y-52532D01*
G01X1032429Y-73240D02*
X1033958Y-74407D01*
X1035704Y-74698D01*
X1037232Y-74407D01*
X1038543Y-72949D01*
X1039416Y-70907D01*
Y-57199D01*
G01Y-59532D02*
X1038543Y-58365D01*
X1037232Y-57490D01*
X1035704Y-57199D01*
X1033958Y-57782D01*
X1032866Y-58948D01*
X1031992Y-60990D01*
X1031556Y-63032D01*
X1031774Y-64782D01*
X1032648Y-66824D01*
X1033958Y-68282D01*
X1035704Y-68865D01*
X1037014Y-68573D01*
X1038543Y-67407D01*
X1039416Y-66241D01*
G01X1049274Y-68865D02*
Y-57199D01*
G01Y-60115D02*
X1050148Y-58657D01*
X1051458Y-57490D01*
X1053204Y-57199D01*
X1054732Y-57490D01*
X1056043Y-58657D01*
X1056698Y-60698D01*
Y-68865D01*
G01X1067211Y-60990D02*
X1074198D01*
X1073543Y-58948D01*
X1072451Y-57782D01*
X1070923Y-57199D01*
X1069394Y-57490D01*
X1068084Y-58365D01*
X1067211Y-60407D01*
X1066774Y-62157D01*
Y-63907D01*
X1067211Y-65657D01*
X1068303Y-67407D01*
X1069613Y-68573D01*
X1071141Y-68865D01*
X1072669Y-68282D01*
X1074198Y-66532D01*
G01X1084929Y-68865D02*
Y-57199D01*
G01Y-59532D02*
X1086021Y-58365D01*
X1087113Y-57490D01*
X1088641Y-57199D01*
X1089732Y-57490D01*
X1091043Y-58365D01*
G01X1131686Y-113865D02*
Y-96365D01*
X1129066Y-99865D01*
G01Y-113865D02*
X1134306D01*
G01X1149186D02*
Y-96365D01*
X1146566Y-99865D01*
G01Y-113865D02*
X1151806D01*
G01X1162756Y-114448D02*
X1170616Y-96365D01*
G01X1184186Y-113865D02*
Y-96365D01*
X1181566Y-99865D01*
G01Y-113865D02*
X1186806D01*
G01X1196883Y-110365D02*
X1198192Y-112407D01*
X1199939Y-113573D01*
X1201904Y-113865D01*
X1203651Y-113573D01*
X1205398Y-112115D01*
X1206489Y-110365D01*
X1206708Y-108615D01*
X1206271Y-106574D01*
X1204743Y-105115D01*
X1203214Y-104532D01*
X1201249D01*
G01X1203214D02*
X1204524Y-103657D01*
X1205616Y-102199D01*
X1206053Y-100449D01*
X1205616Y-98698D01*
X1204524Y-97240D01*
X1202559Y-96365D01*
X1200594Y-96657D01*
X1198629Y-97824D01*
G01X1215256Y-114448D02*
X1223116Y-96365D01*
G01X1232538Y-99282D02*
X1233848Y-97532D01*
X1235376Y-96657D01*
X1237123Y-96365D01*
X1239306Y-96948D01*
X1240834Y-98407D01*
X1241271Y-100156D01*
X1241053Y-101907D01*
X1240179Y-103365D01*
X1235813Y-106282D01*
X1233848Y-108323D01*
X1232538Y-111241D01*
X1232101Y-113865D01*
X1241271D01*
G01X1254186Y-96365D02*
X1252439Y-96948D01*
X1251129Y-98407D01*
X1250256Y-100156D01*
X1249601Y-102490D01*
X1249383Y-105115D01*
X1249601Y-107740D01*
X1250256Y-110074D01*
X1251129Y-111824D01*
X1252439Y-113282D01*
X1254186Y-113865D01*
X1255932Y-113282D01*
X1257243Y-111824D01*
X1258116Y-110074D01*
X1258771Y-107740D01*
X1258989Y-105115D01*
X1258771Y-102490D01*
X1258116Y-100156D01*
X1257243Y-98407D01*
X1255932Y-96948D01*
X1254186Y-96365D01*
G01X1271686Y-113865D02*
Y-96365D01*
X1269066Y-99865D01*
G01Y-113865D02*
X1274306D01*
G01X1291806D02*
Y-96365D01*
X1283727Y-108907D01*
X1294645D01*
G01X1179383Y-68865D02*
Y-51365D01*
X1183749D01*
X1185496Y-52240D01*
X1186806Y-53407D01*
X1187898Y-55156D01*
X1188771Y-57199D01*
X1188989Y-60115D01*
X1188771Y-63032D01*
X1187898Y-65074D01*
X1186806Y-66824D01*
X1185496Y-67990D01*
X1183749Y-68865D01*
X1179383D01*
G01X1205616D02*
Y-57199D01*
G01Y-59240D02*
X1204743Y-58074D01*
X1203432Y-57490D01*
X1201904Y-57199D01*
X1200376Y-57782D01*
X1199066Y-58948D01*
X1198192Y-60698D01*
X1197756Y-63032D01*
X1198192Y-65365D01*
X1199066Y-67115D01*
X1200376Y-68282D01*
X1201904Y-68865D01*
X1203432Y-68573D01*
X1204743Y-67699D01*
X1205616Y-66532D01*
G01X1219186Y-51365D02*
Y-68865D01*
G01X1216129Y-57199D02*
X1222243D01*
G01X1233411Y-60990D02*
X1240398D01*
X1239743Y-58948D01*
X1238651Y-57782D01*
X1237123Y-57199D01*
X1235594Y-57490D01*
X1234284Y-58365D01*
X1233411Y-60407D01*
X1232974Y-62157D01*
Y-63907D01*
X1233411Y-65657D01*
X1234503Y-67407D01*
X1235813Y-68573D01*
X1237341Y-68865D01*
X1238869Y-68282D01*
X1240398Y-66532D01*
G01X773433Y284000D02*
Y286500D01*
X774267D01*
X774600Y286375D01*
X774850Y286208D01*
X775058Y285958D01*
X775225Y285667D01*
X775267Y285250D01*
X775225Y284833D01*
X775058Y284542D01*
X774850Y284292D01*
X774600Y284125D01*
X774267Y284000D01*
X773433D01*
G01X776533D02*
Y286500D01*
X777367D01*
X777700Y286375D01*
X777950Y286208D01*
X778158Y285958D01*
X778325Y285667D01*
X778367Y285250D01*
X778325Y284833D01*
X778158Y284542D01*
X777950Y284292D01*
X777700Y284125D01*
X777367Y284000D01*
X776533D01*
G01X779717D02*
Y286500D01*
X780758D01*
X781092Y286375D01*
X781300Y286208D01*
X781383Y285875D01*
X781300Y285542D01*
X781050Y285333D01*
X780758Y285208D01*
X779717D01*
G01X780758D02*
X781383Y284000D01*
G01X787667Y286292D02*
X787417Y286417D01*
X787125Y286500D01*
X786792D01*
X786417Y286375D01*
X786125Y286167D01*
X785917Y285917D01*
X785750Y285500D01*
X785708Y285125D01*
X785792Y284750D01*
X785917Y284500D01*
X786167Y284250D01*
X786458Y284083D01*
X786750Y284000D01*
X787042D01*
X787333Y284083D01*
X787583Y284208D01*
X787792Y284375D01*
G01X788975Y284000D02*
Y286500D01*
G01X790725D02*
Y284000D01*
G01Y285250D02*
X788975D01*
G01X791908Y284000D02*
X792950Y286500D01*
X793992Y284000D01*
G01X793617Y284875D02*
X792283D01*
G01X794800Y283167D02*
X797300D01*
G01X799150Y284000D02*
Y286500D01*
X798650Y286000D01*
G01Y284000D02*
X799650D01*
G01X784833Y16500D02*
Y19000D01*
X785667D01*
X786000Y18875D01*
X786250Y18708D01*
X786458Y18458D01*
X786625Y18167D01*
X786667Y17750D01*
X786625Y17333D01*
X786458Y17042D01*
X786250Y16792D01*
X786000Y16625D01*
X785667Y16500D01*
X784833D01*
G01X787933D02*
Y19000D01*
X788767D01*
X789100Y18875D01*
X789350Y18708D01*
X789558Y18458D01*
X789725Y18167D01*
X789767Y17750D01*
X789725Y17333D01*
X789558Y17042D01*
X789350Y16792D01*
X789100Y16625D01*
X788767Y16500D01*
X787933D01*
G01X791117D02*
Y19000D01*
X792158D01*
X792492Y18875D01*
X792700Y18708D01*
X792783Y18375D01*
X792700Y18042D01*
X792450Y17833D01*
X792158Y17708D01*
X791117D01*
G01X792158D02*
X792783Y16500D01*
G01X799067Y18792D02*
X798817Y18917D01*
X798525Y19000D01*
X798192D01*
X797817Y18875D01*
X797525Y18667D01*
X797317Y18417D01*
X797150Y18000D01*
X797108Y17625D01*
X797192Y17250D01*
X797317Y17000D01*
X797567Y16750D01*
X797858Y16583D01*
X798150Y16500D01*
X798442D01*
X798733Y16583D01*
X798983Y16708D01*
X799192Y16875D01*
G01X800375Y16500D02*
Y19000D01*
G01X802125D02*
Y16500D01*
G01Y17750D02*
X800375D01*
G01X804683Y17833D02*
X804850Y17958D01*
X804975Y18167D01*
X805058Y18458D01*
X804975Y18708D01*
X804808Y18875D01*
X804517Y19000D01*
X803392D01*
Y16500D01*
X804767D01*
X805058Y16667D01*
X805225Y16917D01*
X805308Y17208D01*
X805225Y17500D01*
X804975Y17750D01*
X804683Y17833D01*
X803392D01*
G01X806200Y15667D02*
X808700D01*
G01X810550Y16500D02*
Y19000D01*
X810050Y18500D01*
G01Y16500D02*
X811050D01*
M02*
